(kicad_pcb
	(version 20241229)
	(generator "pcbnew")
	(generator_version "9.0")
	(general
		(thickness 1.599998)
		(legacy_teardrops no)
	)
	(paper "A4")
	(title_block
		(title "Artix - Datacenter Secure Control Module (DC-SCM)")
		(date "2024-11-06")
		(rev "1.1.3")
		(comment 9 "footprints 192-197 of 544")
	)
	(layers
		(0 "F.Cu" signal)
		(4 "In1.Cu" signal)
		(6 "In2.Cu" signal)
		(8 "In3.Cu" signal)
		(10 "In4.Cu" signal)
		(12 "In5.Cu" signal)
		(14 "In6.Cu" signal)
		(2 "B.Cu" signal)
		(9 "F.Adhes" user "F.Adhesive")
		(11 "B.Adhes" user "B.Adhesive")
		(13 "F.Paste" user)
		(15 "B.Paste" user)
		(5 "F.SilkS" user "F.Silkscreen")
		(7 "B.SilkS" user "B.Silkscreen")
		(1 "F.Mask" user)
		(3 "B.Mask" user)
		(17 "Dwgs.User" user "User.Drawings")
		(19 "Cmts.User" user "User.Comments")
		(21 "Eco1.User" user "User.Eco1")
		(23 "Eco2.User" user "User.Eco2")
		(25 "Edge.Cuts" user)
		(27 "Margin" user)
		(31 "F.CrtYd" user "F.Courtyard")
		(29 "B.CrtYd" user "B.Courtyard")
		(35 "F.Fab" user)
		(33 "B.Fab" user)
	)
	(footprint "antmicro-footprints:LED_0603_1608Metric_G"
		(layer "F.Cu")
		(at 138.99 61.165 90)
		(descr "LED SMD 0603 Green")
		(tags "LED SMD 0603 Green")
		(property "Reference" "D11"
			(at -1.435 5.61 90)
			(layer "F.SilkS")
			(effects
				(font
					(size 0.7 0.7)
					(thickness 0.15)
				)
				(justify left bottom)
			)
		)
		(property "Value" "LED_G_0603_LG_L29K-G2J1-24-Z"
			(at 0 1.6 90)
			(layer "F.Fab")
			(effects
				(font
					(size 0.7 0.7)
					(thickness 0.15)
				)
				(justify left bottom)
			)
		)
		(property "Datasheet" "https://look.ams-osram.com/m/19ee86b3ae0ee95b/original/LG-L29K.pdf"
			(at 0 0 90)
			(layer "F.Fab")
			(hide yes)
			(effects
				(font
					(size 1.27 1.27)
					(thickness 0.15)
				)
			)
		)
		(property "Description" "LED, Green, SMD, 0603, 20 mA, 1.7 V, 570 nm"
			(at 0 0 90)
			(layer "F.Fab")
			(hide yes)
			(effects
				(font
					(size 1.27 1.27)
					(thickness 0.15)
				)
			)
		)
		(property "Author" "Antmicro"
			(at 200.155 -77.825 0)
			(layer "F.Fab")
			(hide yes)
			(effects
				(font
					(size 1 1)
					(thickness 0.15)
				)
			)
		)
		(property "Color" "Green"
			(at 200.155 -77.825 0)
			(layer "F.Fab")
			(hide yes)
			(effects
				(font
					(size 1 1)
					(thickness 0.15)
				)
			)
		)
		(property "License" "Apache-2.0"
			(at 200.155 -77.825 0)
			(layer "F.Fab")
			(hide yes)
			(effects
				(font
					(size 1 1)
					(thickness 0.15)
				)
			)
		)
		(property "MPN" "LG L29K-G2J1-24-Z"
			(at 200.155 -77.825 0)
			(layer "F.Fab")
			(hide yes)
			(effects
				(font
					(size 1 1)
					(thickness 0.15)
				)
			)
		)
		(property "Manufacturer" "OSRAM"
			(at 200.155 -77.825 0)
			(layer "F.Fab")
			(hide yes)
			(effects
				(font
					(size 1 1)
					(thickness 0.15)
				)
			)
		)
		(sheetname "/FPGA banks 34-35 & CFG/")
		(sheetfile "fpga-banks-34-25-cfg.kicad_sch")
		(attr smd)
		(fp_line
			(start 0.22 -0.35)
			(end -0.22 -0.35)
			(stroke
				(width 0.15)
				(type solid)
			)
			(layer "F.SilkS")
		)
		(fp_line
			(start -1.18 -0.319)
			(end -1.18 0.321)
			(stroke
				(width 0.15)
				(type solid)
			)
			(layer "F.SilkS")
		)
		(fp_line
			(start 0.105328 0.001008)
			(end 0.24 0.001)
			(stroke
				(width 0.1)
				(type solid)
			)
			(layer "F.SilkS")
		)
		(fp_line
			(start -0.094672 0.001008)
			(end 0.105328 -0.198992)
			(stroke
				(width 0.1)
				(type solid)
			)
			(layer "F.SilkS")
		)
		(fp_line
			(start -0.094672 0.001008)
			(end -0.24 0.001008)
			(stroke
				(width 0.1)
				(type solid)
			)
			(layer "F.SilkS")
		)
		(fp_line
			(start 0.105328 0.201008)
			(end 0.105328 -0.198992)
			(stroke
				(width 0.1)
				(type solid)
			)
			(layer "F.SilkS")
		)
		(fp_line
			(start 0.105328 0.201008)
			(end -0.094672 0.001008)
			(stroke
				(width 0.1)
				(type solid)
			)
			(layer "F.SilkS")
		)
		(fp_line
			(start -0.094672 0.201008)
			(end -0.094672 -0.198992)
			(stroke
				(width 0.1)
				(type solid)
			)
			(layer "F.SilkS")
		)
		(fp_line
			(start 0.22 0.35)
			(end -0.22 0.35)
			(stroke
				(width 0.15)
				(type solid)
			)
			(layer "F.SilkS")
		)
		(fp_rect
			(start 1.25 0.65)
			(end -1.25 -0.65)
			(stroke
				(width 0.05)
				(type solid)
			)
			(fill no)
			(layer "F.CrtYd")
		)
		(fp_line
			(start 0.201 -0.202)
			(end -0.101 0)
			(stroke
				(width 0.15)
				(type solid)
			)
			(layer "F.Fab")
		)
		(fp_line
			(start -0.199 -0.202)
			(end -0.199 0.1)
			(stroke
				(width 0.15)
				(type solid)
			)
			(layer "F.Fab")
		)
		(fp_line
			(start 0.599 0)
			(end 0.201 0)
			(stroke
				(width 0.15)
				(type solid)
			)
			(layer "F.Fab")
		)
		(fp_line
			(start 0.201 0)
			(end 0.201 -0.202)
			(stroke
				(width 0.15)
				(type solid)
			)
			(layer "F.Fab")
		)
		(fp_line
			(start -0.101 0)
			(end 0.201 0.2)
			(stroke
				(width 0.15)
				(type solid)
			)
			(layer "F.Fab")
		)
		(fp_line
			(start -0.199 0)
			(end -0.597 0)
			(stroke
				(width 0.15)
				(type solid)
			)
			(layer "F.Fab")
		)
		(fp_line
			(start 0.201 0.2)
			(end 0.201 0)
			(stroke
				(width 0.15)
				(type solid)
			)
			(layer "F.Fab")
		)
		(fp_line
			(start -0.199 0.2)
			(end -0.199 0.1)
			(stroke
				(width 0.15)
				(type solid)
			)
			(layer "F.Fab")
		)
		(fp_rect
			(start 0.848 0.4)
			(end -0.85 -0.402)
			(stroke
				(width 0.15)
				(type solid)
			)
			(fill no)
			(layer "F.Fab")
		)
		(pad "1" smd roundrect
			(at -0.7 0 270)
			(size 0.8 1)
			(layers "F.Cu" "F.Mask" "F.Paste")
			(roundrect_rratio 0.2)
			(net 284 "Net-(D11-C)")
			(pinfunction "C")
			(pintype "passive")
		)
		(pad "2" smd roundrect
			(at 0.7 0 270)
			(size 0.8 1)
			(layers "F.Cu" "F.Mask" "F.Paste")
			(roundrect_rratio 0.2)
			(net 286 "Net-(D11-A)")
			(pinfunction "A")
			(pintype "passive")
		)
	)
	(footprint "antmicro-footprints:C_0402_1005Metric"
		(layer "F.Cu")
		(at 85.6 110.57 180)
		(descr "Capacitor SMD 0402")
		(tags "capacitor SMD 0402")
		(property "Reference" "C233"
			(at -1.78 0.545 0)
			(layer "F.SilkS")
			(effects
				(font
					(size 0.7 0.7)
					(thickness 0.15)
				)
				(justify right bottom)
			)
		)
		(property "Value" "C_100n_0402"
			(at 0 1.4 0)
			(layer "F.Fab")
			(effects
				(font
					(size 0.7 0.7)
					(thickness 0.15)
				)
				(justify right bottom)
			)
		)
		(property "Datasheet" "https://www.murata.com/products/productdetail?partno=GRM155R61H104KE14%23"
			(at 0 0 180)
			(layer "F.Fab")
			(hide yes)
			(effects
				(font
					(size 1.27 1.27)
					(thickness 0.15)
				)
			)
		)
		(property "Description" "SMD Multilayer Ceramic Capacitor, 0.1 µF, 50 V, 0402 [1005 Metric], ± 10%, X5R, GRM Series"
			(at 0 0 180)
			(layer "F.Fab")
			(hide yes)
			(effects
				(font
					(size 1.27 1.27)
					(thickness 0.15)
				)
			)
		)
		(property "Author" "Antmicro"
			(at 171.2 221.14 0)
			(layer "F.Fab")
			(hide yes)
			(effects
				(font
					(size 1 1)
					(thickness 0.15)
				)
			)
		)
		(property "Dielectric" "X5R"
			(at 171.2 221.14 0)
			(layer "F.Fab")
			(hide yes)
			(effects
				(font
					(size 1 1)
					(thickness 0.15)
				)
			)
		)
		(property "License" "Apache-2.0"
			(at 171.2 221.14 0)
			(layer "F.Fab")
			(hide yes)
			(effects
				(font
					(size 1 1)
					(thickness 0.15)
				)
			)
		)
		(property "MPN" "GRM155R61H104KE14D"
			(at 171.2 221.14 0)
			(layer "F.Fab")
			(hide yes)
			(effects
				(font
					(size 1 1)
					(thickness 0.15)
				)
			)
		)
		(property "Manufacturer" "Murata"
			(at 171.2 221.14 0)
			(layer "F.Fab")
			(hide yes)
			(effects
				(font
					(size 1 1)
					(thickness 0.15)
				)
			)
		)
		(property "Val" "100n"
			(at 171.2 221.14 0)
			(layer "F.Fab")
			(hide yes)
			(effects
				(font
					(size 1 1)
					(thickness 0.15)
				)
			)
		)
		(property "Voltage" "50V"
			(at 171.2 221.14 0)
			(layer "F.Fab")
			(hide yes)
			(effects
				(font
					(size 1 1)
					(thickness 0.15)
				)
			)
		)
		(property "DNP" ""
			(at 0 0 180)
			(unlocked yes)
			(layer "F.Fab")
			(hide yes)
			(effects
				(font
					(size 1 1)
					(thickness 0.15)
				)
			)
		)
		(sheetname "/FPGA banks 13-16/")
		(sheetfile "fpga-banks-13-16.kicad_sch")
		(attr smd)
		(fp_rect
			(start -0.925 -0.47)
			(end 0.925 0.47)
			(stroke
				(width 0.05)
				(type default)
			)
			(fill no)
			(layer "F.CrtYd")
		)
		(fp_line
			(start 0.504 0.248)
			(end -0.494 0.248)
			(stroke
				(width 0.15)
				(type solid)
			)
			(layer "F.Fab")
		)
		(fp_line
			(start 0.504 -0.25)
			(end 0.504 0.248)
			(stroke
				(width 0.15)
				(type solid)
			)
			(layer "F.Fab")
		)
		(fp_line
			(start -0.494 0.248)
			(end -0.494 -0.25)
			(stroke
				(width 0.15)
				(type solid)
			)
			(layer "F.Fab")
		)
		(fp_line
			(start -0.494 -0.25)
			(end 0.504 -0.25)
			(stroke
				(width 0.15)
				(type solid)
			)
			(layer "F.Fab")
		)
		(pad "1" smd roundrect
			(at -0.48 0 180)
			(size 0.59 0.64)
			(layers "F.Cu" "F.Mask" "F.Paste")
			(roundrect_rratio 0.25)
			(net 1 "GND")
			(pintype "passive")
		)
		(pad "2" smd roundrect
			(at 0.48 0 180)
			(size 0.59 0.64)
			(layers "F.Cu" "F.Mask" "F.Paste")
			(roundrect_rratio 0.25)
			(net 2 "VCC3V3")
			(pintype "passive")
		)
	)
	(footprint "antmicro-footprints:Oscillator_SMD_Abracon_AMJM_3.2x2.5mm"
		(layer "F.Cu")
		(at 82.938 111.624)
		(descr "Oscillator SMD, AMJM, 3.2x2.5mm")
		(property "Reference" "U15"
			(at -1.863 -2.374 0)
			(layer "F.SilkS")
			(effects
				(font
					(size 0.7 0.7)
					(thickness 0.15)
				)
				(justify left bottom)
			)
		)
		(property "Value" "Oscillator_100MHz_AMJMEFB"
			(at 1.05 3.798 0)
			(layer "F.Fab")
			(effects
				(font
					(size 0.7 0.7)
					(thickness 0.15)
				)
				(justify left bottom)
			)
		)
		(property "Datasheet" "https://abracon.com/datasheets/AMJM.pdf"
			(at 0 0 0)
			(layer "F.Fab")
			(hide yes)
			(effects
				(font
					(size 1.27 1.27)
					(thickness 0.15)
				)
			)
		)
		(property "Description" "MEMS Oscillator, 100 MHz, SMT, 3.2mm x 2.5mm, 25 ppm, 2.5 V, AMJM"
			(at 0 0 0)
			(layer "F.Fab")
			(hide yes)
			(effects
				(font
					(size 1.27 1.27)
					(thickness 0.15)
				)
			)
		)
		(property "Author" "Antmicro"
			(at 0 0 0)
			(layer "F.Fab")
			(hide yes)
			(effects
				(font
					(size 1 1)
					(thickness 0.15)
				)
			)
		)
		(property "License" "Apache-2.0"
			(at 0 0 0)
			(layer "F.Fab")
			(hide yes)
			(effects
				(font
					(size 1 1)
					(thickness 0.15)
				)
			)
		)
		(property "MPN" "AMJMEFB-100.0000T"
			(at 0 0 0)
			(layer "F.Fab")
			(hide yes)
			(effects
				(font
					(size 1 1)
					(thickness 0.15)
				)
			)
		)
		(property "Manufacturer" "Abracon"
			(at 0 0 0)
			(layer "F.Fab")
			(hide yes)
			(effects
				(font
					(size 1 1)
					(thickness 0.15)
				)
			)
		)
		(property "Val" "100 MHz"
			(at 0 0 0)
			(layer "F.Fab")
			(hide yes)
			(effects
				(font
					(size 1 1)
					(thickness 0.15)
				)
			)
		)
		(sheetname "/FPGA banks 13-16/")
		(sheetfile "fpga-banks-13-16.kicad_sch")
		(attr smd)
		(fp_circle
			(center -1.448 -1.754)
			(end -1.397 -1.754)
			(stroke
				(width 0.15)
				(type solid)
			)
			(fill yes)
			(layer "F.SilkS")
		)
		(fp_rect
			(start -1.5 -1.8)
			(end 1.6 1.8)
			(stroke
				(width 0.05)
				(type solid)
			)
			(fill no)
			(layer "F.CrtYd")
		)
		(fp_line
			(start -0.977 -0.822)
			(end -0.554 -1.246)
			(stroke
				(width 0.15)
				(type solid)
			)
			(layer "F.Fab")
		)
		(pad "1" smd roundrect
			(at -0.876 -1.045)
			(size 1 0.9)
			(layers "F.Cu" "F.Mask" "F.Paste")
			(roundrect_rratio 0.1)
			(chamfer_ratio 0.2)
			(chamfer top_left)
			(net 2 "VCC3V3")
			(pinfunction "EN")
			(pintype "input")
		)
		(pad "2" smd roundrect
			(at -0.876 1.056)
			(size 1 0.9)
			(layers "F.Cu" "F.Mask" "F.Paste")
			(roundrect_rratio 0.1)
			(net 1 "GND")
			(pinfunction "GND")
			(pintype "power_in")
		)
		(pad "3" smd roundrect
			(at 0.922 1.056)
			(size 1 0.9)
			(layers "F.Cu" "F.Mask" "F.Paste")
			(roundrect_rratio 0.1)
			(net 503 "/FPGA banks 13-16/GCLK100")
			(pinfunction "OUT")
			(pintype "output")
		)
		(pad "4" smd roundrect
			(at 0.922 -1.045)
			(size 1 0.9)
			(layers "F.Cu" "F.Mask" "F.Paste")
			(roundrect_rratio 0.1)
			(net 2 "VCC3V3")
			(pinfunction "VDD")
			(pintype "power_in")
		)
	)
	(footprint "antmicro-footprints:C_0402_1005Metric"
		(layer "F.Cu")
		(at 132.275 154.43 -90)
		(descr "Capacitor SMD 0402")
		(tags "capacitor SMD 0402")
		(property "Reference" "C31"
			(at -2.98 -0.33 90)
			(layer "F.SilkS")
			(effects
				(font
					(size 0.7 0.7)
					(thickness 0.15)
				)
				(justify right bottom)
			)
		)
		(property "Value" "C_10u_0402"
			(at 0 1.4 90)
			(layer "F.Fab")
			(effects
				(font
					(size 0.7 0.7)
					(thickness 0.15)
				)
				(justify right bottom)
			)
		)
		(property "Datasheet" "https://www.yageo.com/en/Chart/Download/pdf/CC0402MRX5R5BB106"
			(at 0 0 270)
			(layer "F.Fab")
			(hide yes)
			(effects
				(font
					(size 1.27 1.27)
					(thickness 0.15)
				)
			)
		)
		(property "Description" "SMD Multilayer Ceramic Capacitor, 10 µF, 6.3 V, 0402 [1005 Metric], ± 20%, X5R, CC Series"
			(at 0 0 270)
			(layer "F.Fab")
			(hide yes)
			(effects
				(font
					(size 1.27 1.27)
					(thickness 0.15)
				)
			)
		)
		(property "Author" "Antmicro"
			(at -22.155 286.705 0)
			(layer "F.Fab")
			(hide yes)
			(effects
				(font
					(size 1 1)
					(thickness 0.15)
				)
			)
		)
		(property "Dielectric" ""
			(at -22.155 286.705 0)
			(layer "F.Fab")
			(hide yes)
			(effects
				(font
					(size 1 1)
					(thickness 0.15)
				)
			)
		)
		(property "License" "Apache-2.0"
			(at -22.155 286.705 0)
			(layer "F.Fab")
			(hide yes)
			(effects
				(font
					(size 1 1)
					(thickness 0.15)
				)
			)
		)
		(property "MPN" "CC0402MRX5R5BB106"
			(at -22.155 286.705 0)
			(layer "F.Fab")
			(hide yes)
			(effects
				(font
					(size 1 1)
					(thickness 0.15)
				)
			)
		)
		(property "Manufacturer" "YAGEO"
			(at -22.155 286.705 0)
			(layer "F.Fab")
			(hide yes)
			(effects
				(font
					(size 1 1)
					(thickness 0.15)
				)
			)
		)
		(property "Val" "10u"
			(at -22.155 286.705 0)
			(layer "F.Fab")
			(hide yes)
			(effects
				(font
					(size 1 1)
					(thickness 0.15)
				)
			)
		)
		(property "Voltage" ""
			(at -22.155 286.705 0)
			(layer "F.Fab")
			(hide yes)
			(effects
				(font
					(size 1 1)
					(thickness 0.15)
				)
			)
		)
		(sheetname "/PCIe-connector/")
		(sheetfile "pcie-conn.kicad_sch")
		(attr smd)
		(fp_rect
			(start -0.925 -0.47)
			(end 0.925 0.47)
			(stroke
				(width 0.05)
				(type default)
			)
			(fill no)
			(layer "F.CrtYd")
		)
		(fp_line
			(start -0.494 0.248)
			(end -0.494 -0.25)
			(stroke
				(width 0.15)
				(type solid)
			)
			(layer "F.Fab")
		)
		(fp_line
			(start 0.504 0.248)
			(end -0.494 0.248)
			(stroke
				(width 0.15)
				(type solid)
			)
			(layer "F.Fab")
		)
		(fp_line
			(start -0.494 -0.25)
			(end 0.504 -0.25)
			(stroke
				(width 0.15)
				(type solid)
			)
			(layer "F.Fab")
		)
		(fp_line
			(start 0.504 -0.25)
			(end 0.504 0.248)
			(stroke
				(width 0.15)
				(type solid)
			)
			(layer "F.Fab")
		)
		(pad "1" smd roundrect
			(at -0.48 0 270)
			(size 0.59 0.64)
			(layers "F.Cu" "F.Mask" "F.Paste")
			(roundrect_rratio 0.25)
			(net 1 "GND")
			(pintype "passive")
		)
		(pad "2" smd roundrect
			(at 0.48 0 270)
			(size 0.59 0.64)
			(layers "F.Cu" "F.Mask" "F.Paste")
			(roundrect_rratio 0.25)
			(net 2 "VCC3V3")
			(pintype "passive")
		)
	)
	(footprint "antmicro-footprints:R_0402_1005Metric"
		(layer "F.Cu")
		(at 78 73.705)
		(descr "Resistor SMD 0402")
		(tags "resistor SMD 0402")
		(property "Reference" "R70"
			(at -17.7 -1.505 0)
			(layer "F.SilkS")
			(effects
				(font
					(size 0.7 0.7)
					(thickness 0.15)
				)
				(justify left bottom)
			)
		)
		(property "Value" "R_49R9_0402"
			(at 0 1.4 0)
			(layer "F.Fab")
			(effects
				(font
					(size 0.7 0.7)
					(thickness 0.15)
				)
				(justify left bottom)
			)
		)
		(property "Datasheet" "https://www.bourns.com/docs/product-datasheets/cr.pdf"
			(at 0 0 0)
			(layer "F.Fab")
			(hide yes)
			(effects
				(font
					(size 1.27 1.27)
					(thickness 0.15)
				)
			)
		)
		(property "Description" "SMD Chip Resistor, 49.9 ohm, ± 1%, 62.5 mW, 0402 [1005 Metric], Thick Film, General Purpose"
			(at 0 0 0)
			(layer "F.Fab")
			(hide yes)
			(effects
				(font
					(size 1.27 1.27)
					(thickness 0.15)
				)
			)
		)
		(property "Author" "Antmicro"
			(at 0 0 0)
			(layer "F.Fab")
			(hide yes)
			(effects
				(font
					(size 1 1)
					(thickness 0.15)
				)
			)
		)
		(property "License" "Apache-2.0"
			(at 0 0 0)
			(layer "F.Fab")
			(hide yes)
			(effects
				(font
					(size 1 1)
					(thickness 0.15)
				)
			)
		)
		(property "MPN" "CR0402-FX-49R9GLF"
			(at 0 0 0)
			(layer "F.Fab")
			(hide yes)
			(effects
				(font
					(size 1 1)
					(thickness 0.15)
				)
			)
		)
		(property "Manufacturer" "Bourns"
			(at 0 0 0)
			(layer "F.Fab")
			(hide yes)
			(effects
				(font
					(size 1 1)
					(thickness 0.15)
				)
			)
		)
		(property "Tolerance" "1%"
			(at 0 0 0)
			(layer "F.Fab")
			(hide yes)
			(effects
				(font
					(size 1 1)
					(thickness 0.15)
				)
			)
		)
		(property "Val" "49R9"
			(at 0 0 0)
			(layer "F.Fab")
			(hide yes)
			(effects
				(font
					(size 1 1)
					(thickness 0.15)
				)
			)
		)
		(sheetname "/Power supply/")
		(sheetfile "power-supply.kicad_sch")
		(attr smd)
		(fp_rect
			(start -0.925 -0.47)
			(end 0.925 0.47)
			(stroke
				(width 0.05)
				(type default)
			)
			(fill no)
			(layer "F.CrtYd")
		)
		(fp_rect
			(start -0.5 -0.25)
			(end 0.5 0.25)
			(stroke
				(width 0.15)
				(type solid)
			)
			(fill no)
			(layer "F.Fab")
		)
		(pad "1" smd roundrect
			(at -0.48 0)
			(size 0.59 0.64)
			(layers "F.Cu" "F.Mask" "F.Paste")
			(roundrect_rratio 0.25)
			(net 114 "Net-(C72-Pad2)")
			(pintype "passive")
		)
		(pad "2" smd roundrect
			(at 0.48 0)
			(size 0.59 0.64)
			(layers "F.Cu" "F.Mask" "F.Paste")
			(roundrect_rratio 0.25)
			(net 205 "Net-(R70-Pad2)")
			(pintype "passive")
		)
	)
	(footprint "antmicro-footprints:TP_SMD_1mm"
		(layer "F.Cu")
		(at 124.95 66.7808)
		(property "Reference" "TP7"
			(at 0.55 0.4192 0)
			(layer "F.SilkS")
			(effects
				(font
					(size 0.7 0.7)
					(thickness 0.15)
				)
				(justify left bottom)
			)
		)
		(property "Value" "TP_1mm_SMD"
			(at 0 1.4 0)
			(layer "F.Fab")
			(effects
				(font
					(size 0.7 0.7)
					(thickness 0.15)
				)
				(justify left bottom)
			)
		)
		(property "Description" "Test point 1mm SMD"
			(at 0 0 0)
			(layer "F.Fab")
			(hide yes)
			(effects
				(font
					(size 1.27 1.27)
					(thickness 0.15)
				)
			)
		)
		(property "Author" "Antmicro"
			(at 0 0 0)
			(layer "F.Fab")
			(hide yes)
			(effects
				(font
					(size 1 1)
					(thickness 0.15)
				)
			)
		)
		(property "License" "Apache-2.0"
			(at 0 0 0)
			(layer "F.Fab")
			(hide yes)
			(effects
				(font
					(size 1 1)
					(thickness 0.15)
				)
			)
		)
		(property "MPN" ""
			(at 0 0 0)
			(layer "F.Fab")
			(hide yes)
			(effects
				(font
					(size 1 1)
					(thickness 0.15)
				)
			)
		)
		(property "Manufacturer" ""
			(at 0 0 0)
			(layer "F.Fab")
			(hide yes)
			(effects
				(font
					(size 1 1)
					(thickness 0.15)
				)
			)
		)
		(sheetname "/Interfaces/")
		(sheetfile "interfaces.kicad_sch")
		(attr exclude_from_pos_files exclude_from_bom)
		(fp_circle
			(center 0 0)
			(end 0.6 0)
			(stroke
				(width 0.05)
				(type default)
			)
			(fill no)
			(layer "F.CrtYd")
		)
		(pad "1" smd circle
			(at 0 0)
			(size 1 1)
			(layers "F.Cu" "F.Mask")
			(net 282 "Net-(J3-ID)")
			(pinfunction "1")
			(pintype "passive")
		)
	)
)
